# BASEBOARD_FAB2 (Tioga Pass) — schematic netlist excerpt (pin names and nets, part order shuffled) for the footprints in the layout excerpt that follows; sources: Cadence DE-HDL packaged netlist, KiCad conversion of Wiwynn_Tioga_Pass_MB.brd

R4P20  RES  150.0 1% CHIP  pkg 0402  page 152 : A = H_CPU0_MEMDEF_MEMHOT_G_N ; B = PVCCIO_CPU0
R7P1  RES  42.2 1.0% EMPTY  pkg 0402  page 103 : A = CLK_100M_CPU1_BCLK2_DP ; B = GND
R6P2  RES  42.2 1.0% EMPTY  pkg 0402  page 103 : A = CLK_100M_CPU0_RC_REFCLK0_DN ; B = GND

(kicad_pcb
	(version 20260206)
	(generator "pcbnew")
	(generator_version "10.0")
	(general
		(thickness 1.6)
		(legacy_teardrops no)
	)
	(paper "A4")
	(title_block
		(title "Wiwynn_Tioga_Pass_MB.brd")
		(comment 1 "Tioga Pass / footprints 3426-3428 of 4770")
	)
	(layers
		(0 "F.Cu" signal "TOP")
		(4 "In1.Cu" signal "L2GND")
		(6 "In2.Cu" signal "L3")
		(8 "In3.Cu" signal "L4GND")
		(10 "In4.Cu" signal "L5")
		(12 "In5.Cu" signal "L6GND")
		(14 "In6.Cu" signal "L7VCC")
		(16 "In7.Cu" signal "L8VCC")
		(18 "In8.Cu" signal "L9GND")
		(20 "In9.Cu" signal "L10")
		(22 "In10.Cu" signal "L11GND")
		(24 "In11.Cu" signal "L12")
		(26 "In12.Cu" signal "L13GND")
		(2 "B.Cu" signal "BOTTOM")
		(9 "F.Adhes" user "F.Adhesive")
		(11 "B.Adhes" user "B.Adhesive")
		(13 "F.Paste" user "Package Geometry/Pastemask Top")
		(15 "B.Paste" user "Package Geometry/Pastemask Bottom")
		(5 "F.SilkS" user "Ref Des/Silkscreen Top")
		(7 "B.SilkS" user "Ref Des/Silkscreen Bottom")
		(1 "F.Mask" user "Board Geometry/Soldermask Top")
		(3 "B.Mask" user "Board Geometry/Soldermask Bottom")
		(17 "Dwgs.User" user "User.Drawings")
		(19 "Cmts.User" user "User.Comments")
		(21 "Eco1.User" user "User.Eco1")
		(23 "Eco2.User" user "User.Eco2")
		(25 "Edge.Cuts" user "Board Geometry/Outline")
		(27 "Margin" user)
		(31 "F.CrtYd" user "Package Geometry/Place Bound Top")
		(29 "B.CrtYd" user "Package Geometry/Place Bound Bottom")
		(35 "F.Fab" user "Ref Des/Assembly Top")
		(33 "B.Fab" user "Ref Des/Assembly Bottom")
	)
	(footprint ""
		(layer "B.Cu")
		(at 172.466 -87.757)
		(property "Reference" "R6P2"
			(at 0 0 0)
			(layer "B.SilkS")
			(hide yes)
			(effects
				(font
					(size 1.27 1.27)
				)
				(justify mirror)
			)
		)
		(property "Value" ""
			(at 0 0 0)
			(layer "B.Fab")
			(effects
				(font
					(size 1.27 1.27)
				)
				(justify mirror)
			)
		)
		(duplicate_pad_numbers_are_jumpers no)
		(fp_poly
			(pts
				(xy 0.2794 -0.1016) (xy -0.2794 -0.1016) (xy -0.2794 0.9906) (xy 0.2794 0.9906)
			)
			(stroke
				(width 0)
				(type default)
			)
			(fill no)
			(layer "B.CrtYd")
		)
		(fp_line
			(start -0.2794 -0.1016)
			(end 0.2794 -0.1016)
			(stroke
				(width 0.1)
				(type default)
			)
			(layer "B.Fab")
		)
		(fp_line
			(start -0.2794 0.9906)
			(end -0.2794 -0.1016)
			(stroke
				(width 0.1)
				(type default)
			)
			(layer "B.Fab")
		)
		(fp_line
			(start 0.2794 -0.1016)
			(end 0.2794 0.9906)
			(stroke
				(width 0.1)
				(type default)
			)
			(layer "B.Fab")
		)
		(fp_line
			(start 0.2794 0.9906)
			(end -0.2794 0.9906)
			(stroke
				(width 0.1)
				(type default)
			)
			(layer "B.Fab")
		)
		(pad "1" smd rect
			(at 0 0 180)
			(size 0.508 0.508)
			(layers "B.Cu" "B.Mask" "B.Paste")
			(net "CLK_100M_CPU0_RC_REFCLK0_DN")
		)
		(pad "2" smd rect
			(at 0 0.889 180)
			(size 0.508 0.508)
			(layers "B.Cu" "B.Mask" "B.Paste")
			(net "GND")
		)
		(zone
			(layer "B.Cu")
			(hatch none 0.5)
			(connect_pads
				(clearance 0)
			)
			(min_thickness 0.25)
			(keepout
				(tracks allowed)
				(vias not_allowed)
				(pads allowed)
				(copperpour not_allowed)
				(footprints allowed)
			)
			(placement
				(enabled no)
				(sheetname "")
			)
			(fill
				(thermal_gap 0.5)
				(thermal_bridge_width 0.5)
				(island_removal_mode 0)
			)
			(polygon
				(pts
					(xy 172.72 -87.503) (xy 172.212 -87.503) (xy 172.212 -87.122) (xy 172.72 -87.122)
				)
			)
		)
		(zone
			(layer "B.Cu")
			(hatch none 0.5)
			(connect_pads
				(clearance 0)
			)
			(min_thickness 0.25)
			(keepout
				(tracks not_allowed)
				(vias allowed)
				(pads allowed)
				(copperpour not_allowed)
				(footprints allowed)
			)
			(placement
				(enabled no)
				(sheetname "")
			)
			(fill
				(thermal_gap 0.5)
				(thermal_bridge_width 0.5)
				(island_removal_mode 0)
			)
			(polygon
				(pts
					(xy 172.72 -87.122) (xy 172.212 -87.122) (xy 172.212 -87.503) (xy 172.72 -87.503)
				)
			)
		)
	)
	(footprint ""
		(layer "B.Cu")
		(at 330.984606 -65.303908 -90)
		(property "Reference" "R4P20"
			(at 0 0 90)
			(layer "B.SilkS")
			(hide yes)
			(effects
				(font
					(size 1.27 1.27)
				)
				(justify mirror)
			)
		)
		(property "Value" ""
			(at 0 0 90)
			(layer "B.Fab")
			(effects
				(font
					(size 1.27 1.27)
				)
				(justify mirror)
			)
		)
		(duplicate_pad_numbers_are_jumpers no)
		(fp_poly
			(pts
				(xy 0.2794 -0.1016) (xy -0.2794 -0.1016) (xy -0.2794 0.9906) (xy 0.2794 0.9906)
			)
			(stroke
				(width 0)
				(type default)
			)
			(fill no)
			(layer "B.CrtYd")
		)
		(fp_line
			(start -0.2794 0.9906)
			(end -0.2794 -0.1016)
			(stroke
				(width 0.1)
				(type default)
			)
			(layer "B.Fab")
		)
		(fp_line
			(start 0.2794 0.9906)
			(end -0.2794 0.9906)
			(stroke
				(width 0.1)
				(type default)
			)
			(layer "B.Fab")
		)
		(fp_line
			(start -0.2794 -0.1016)
			(end 0.2794 -0.1016)
			(stroke
				(width 0.1)
				(type default)
			)
			(layer "B.Fab")
		)
		(fp_line
			(start 0.2794 -0.1016)
			(end 0.2794 0.9906)
			(stroke
				(width 0.1)
				(type default)
			)
			(layer "B.Fab")
		)
		(pad "1" smd rect
			(at 0 0 90)
			(size 0.508 0.508)
			(layers "B.Cu" "B.Mask" "B.Paste")
			(net "H_CPU0_MEMDEF_MEMHOT_G_N")
		)
		(pad "2" smd rect
			(at 0 0.889 90)
			(size 0.508 0.508)
			(layers "B.Cu" "B.Mask" "B.Paste")
			(net "PVCCIO_CPU0")
		)
		(zone
			(layer "B.Cu")
			(hatch none 0.5)
			(connect_pads
				(clearance 0)
			)
			(min_thickness 0.25)
			(keepout
				(tracks not_allowed)
				(vias allowed)
				(pads allowed)
				(copperpour not_allowed)
				(footprints allowed)
			)
			(placement
				(enabled no)
				(sheetname "")
			)
			(fill
				(thermal_gap 0.5)
				(thermal_bridge_width 0.5)
				(island_removal_mode 0)
			)
			(polygon
				(pts
					(xy 330.349606 -65.049908) (xy 330.349606 -65.557908) (xy 330.730606 -65.557908) (xy 330.730606 -65.049908)
				)
			)
		)
		(zone
			(layer "B.Cu")
			(hatch none 0.5)
			(connect_pads
				(clearance 0)
			)
			(min_thickness 0.25)
			(keepout
				(tracks allowed)
				(vias not_allowed)
				(pads allowed)
				(copperpour not_allowed)
				(footprints allowed)
			)
			(placement
				(enabled no)
				(sheetname "")
			)
			(fill
				(thermal_gap 0.5)
				(thermal_bridge_width 0.5)
				(island_removal_mode 0)
			)
			(polygon
				(pts
					(xy 330.730606 -65.049908) (xy 330.730606 -65.557908) (xy 330.349606 -65.557908) (xy 330.349606 -65.049908)
				)
			)
		)
	)
	(footprint ""
		(layer "B.Cu")
		(at 162.91306 -85.598 90)
		(property "Reference" "R7P1"
			(at 0 0 90)
			(layer "B.SilkS")
			(hide yes)
			(effects
				(font
					(size 1.27 1.27)
				)
				(justify mirror)
			)
		)
		(property "Value" ""
			(at 0 0 90)
			(layer "B.Fab")
			(effects
				(font
					(size 1.27 1.27)
				)
				(justify mirror)
			)
		)
		(duplicate_pad_numbers_are_jumpers no)
		(fp_poly
			(pts
				(xy 0.2794 -0.1016) (xy -0.2794 -0.1016) (xy -0.2794 0.9906) (xy 0.2794 0.9906)
			)
			(stroke
				(width 0)
				(type default)
			)
			(fill no)
			(layer "B.CrtYd")
		)
		(fp_line
			(start 0.2794 -0.1016)
			(end 0.2794 0.9906)
			(stroke
				(width 0.1)
				(type default)
			)
			(layer "B.Fab")
		)
		(fp_line
			(start -0.2794 -0.1016)
			(end 0.2794 -0.1016)
			(stroke
				(width 0.1)
				(type default)
			)
			(layer "B.Fab")
		)
		(fp_line
			(start 0.2794 0.9906)
			(end -0.2794 0.9906)
			(stroke
				(width 0.1)
				(type default)
			)
			(layer "B.Fab")
		)
		(fp_line
			(start -0.2794 0.9906)
			(end -0.2794 -0.1016)
			(stroke
				(width 0.1)
				(type default)
			)
			(layer "B.Fab")
		)
		(pad "1" smd rect
			(at 0 0 270)
			(size 0.508 0.508)
			(layers "B.Cu" "B.Mask" "B.Paste")
			(net "CLK_100M_CPU1_BCLK2_DP")
		)
		(pad "2" smd rect
			(at 0 0.889 270)
			(size 0.508 0.508)
			(layers "B.Cu" "B.Mask" "B.Paste")
			(net "GND")
		)
		(zone
			(layer "B.Cu")
			(hatch none 0.5)
			(connect_pads
				(clearance 0)
			)
			(min_thickness 0.25)
			(keepout
				(tracks allowed)
				(vias not_allowed)
				(pads allowed)
				(copperpour not_allowed)
				(footprints allowed)
			)
			(placement
				(enabled no)
				(sheetname "")
			)
			(fill
				(thermal_gap 0.5)
				(thermal_bridge_width 0.5)
				(island_removal_mode 0)
			)
			(polygon
				(pts
					(xy 163.16706 -85.852) (xy 163.16706 -85.344) (xy 163.54806 -85.344) (xy 163.54806 -85.852)
				)
			)
		)
		(zone
			(layer "B.Cu")
			(hatch none 0.5)
			(connect_pads
				(clearance 0)
			)
			(min_thickness 0.25)
			(keepout
				(tracks not_allowed)
				(vias allowed)
				(pads allowed)
				(copperpour not_allowed)
				(footprints allowed)
			)
			(placement
				(enabled no)
				(sheetname "")
			)
			(fill
				(thermal_gap 0.5)
				(thermal_bridge_width 0.5)
				(island_removal_mode 0)
			)
			(polygon
				(pts
					(xy 163.54806 -85.852) (xy 163.54806 -85.344) (xy 163.16706 -85.344) (xy 163.16706 -85.852)
				)
			)
		)
	)
)
